(kicad_pcb
	(version 20260206)
	(generator "pcbnew")
	(generator_version "10.0")
	(general
		(thickness 1.6)
		(legacy_teardrops no)
	)
	(paper "A4")
	(title_block
		(title "Wiwynn_Tioga_Pass_MB.brd")
		(comment 1 "Tioga Pass / footprints 2097-2104 of 4770")
	)
	(layers
		(0 "F.Cu" signal "TOP")
		(4 "In1.Cu" signal "L2GND")
		(6 "In2.Cu" signal "L3")
		(8 "In3.Cu" signal "L4GND")
		(10 "In4.Cu" signal "L5")
		(12 "In5.Cu" signal "L6GND")
		(14 "In6.Cu" signal "L7VCC")
		(16 "In7.Cu" signal "L8VCC")
		(18 "In8.Cu" signal "L9GND")
		(20 "In9.Cu" signal "L10")
		(22 "In10.Cu" signal "L11GND")
		(24 "In11.Cu" signal "L12")
		(26 "In12.Cu" signal "L13GND")
		(2 "B.Cu" signal "BOTTOM")
		(9 "F.Adhes" user "F.Adhesive")
		(11 "B.Adhes" user "B.Adhesive")
		(13 "F.Paste" user "Package Geometry/Pastemask Top")
		(15 "B.Paste" user "Package Geometry/Pastemask Bottom")
		(5 "F.SilkS" user "Ref Des/Silkscreen Top")
		(7 "B.SilkS" user "Ref Des/Silkscreen Bottom")
		(1 "F.Mask" user "Board Geometry/Soldermask Top")
		(3 "B.Mask" user "Board Geometry/Soldermask Bottom")
		(17 "Dwgs.User" user "User.Drawings")
		(19 "Cmts.User" user "User.Comments")
		(21 "Eco1.User" user "User.Eco1")
		(23 "Eco2.User" user "User.Eco2")
		(25 "Edge.Cuts" user "Board Geometry/Outline")
		(27 "Margin" user)
		(31 "F.CrtYd" user "Package Geometry/Place Bound Top")
		(29 "B.CrtYd" user "Package Geometry/Place Bound Bottom")
		(35 "F.Fab" user "Ref Des/Assembly Top")
		(33 "B.Fab" user "Ref Des/Assembly Bottom")
	)
	(footprint ""
		(layer "F.Cu")
		(at 30.583378 -22.160992 90)
		(property "Reference" "C1F22"
			(at 0 0 90)
			(layer "F.SilkS")
			(hide yes)
			(effects
				(font
					(size 1.27 1.27)
				)
			)
		)
		(property "Value" ""
			(at 0 0 90)
			(layer "F.Fab")
			(effects
				(font
					(size 1.27 1.27)
				)
			)
		)
		(duplicate_pad_numbers_are_jumpers no)
		(fp_poly
			(pts
				(xy 0.3048 -0.1016) (xy 0.3048 0.9906) (xy -0.3048 0.9906) (xy -0.3048 -0.1016)
			)
			(stroke
				(width 0)
				(type default)
			)
			(fill no)
			(layer "F.CrtYd")
		)
		(fp_line
			(start 0.3048 -0.1016)
			(end -0.3048 -0.1016)
			(stroke
				(width 0.1)
				(type default)
			)
			(layer "F.Fab")
		)
		(fp_line
			(start -0.3048 -0.1016)
			(end -0.3048 0.9906)
			(stroke
				(width 0.1)
				(type default)
			)
			(layer "F.Fab")
		)
		(fp_line
			(start 0.3048 0.9906)
			(end 0.3048 -0.1016)
			(stroke
				(width 0.1)
				(type default)
			)
			(layer "F.Fab")
		)
		(fp_line
			(start -0.3048 0.9906)
			(end 0.3048 0.9906)
			(stroke
				(width 0.1)
				(type default)
			)
			(layer "F.Fab")
		)
		(pad "1" smd rect
			(at 0 0 90)
			(size 0.508 0.508)
			(layers "F.Cu" "F.Mask" "F.Paste")
			(net "M_G_VREF")
		)
		(pad "2" smd rect
			(at 0 0.889 90)
			(size 0.508 0.508)
			(layers "F.Cu" "F.Mask" "F.Paste")
			(net "GND")
		)
		(zone
			(layer "F.Cu")
			(hatch none 0.5)
			(connect_pads
				(clearance 0)
			)
			(min_thickness 0.25)
			(keepout
				(tracks allowed)
				(vias not_allowed)
				(pads allowed)
				(copperpour not_allowed)
				(footprints allowed)
			)
			(placement
				(enabled no)
				(sheetname "")
			)
			(fill
				(thermal_gap 0.5)
				(thermal_bridge_width 0.5)
				(island_removal_mode 0)
			)
			(polygon
				(pts
					(xy 30.837378 -21.906992) (xy 30.837378 -22.414992) (xy 31.218378 -22.414992) (xy 31.218378 -21.906992)
				)
			)
		)
		(zone
			(layer "F.Cu")
			(hatch none 0.5)
			(connect_pads
				(clearance 0)
			)
			(min_thickness 0.25)
			(keepout
				(tracks not_allowed)
				(vias allowed)
				(pads allowed)
				(copperpour not_allowed)
				(footprints allowed)
			)
			(placement
				(enabled no)
				(sheetname "")
			)
			(fill
				(thermal_gap 0.5)
				(thermal_bridge_width 0.5)
				(island_removal_mode 0)
			)
			(polygon
				(pts
					(xy 31.218378 -21.906992) (xy 31.218378 -22.414992) (xy 30.837378 -22.414992) (xy 30.837378 -21.906992)
				)
			)
		)
	)
	(footprint ""
		(layer "F.Cu")
		(at 107.8611 -149.8092 90)
		(property "Reference" "C3A1"
			(at 1.848866 0.752348 90)
			(unlocked yes)
			(layer "F.SilkS")
			(effects
				(font
					(size 1.27 0.9652)
					(thickness 0.1524)
				)
			)
		)
		(property "Value" ""
			(at 0 0 90)
			(layer "F.Fab")
			(effects
				(font
					(size 1.27 1.27)
				)
			)
		)
		(duplicate_pad_numbers_are_jumpers no)
		(fp_rect
			(start -0.500126 1.598422)
			(end 0.500126 -0.201422)
			(stroke
				(width 0)
				(type default)
			)
			(fill no)
			(layer "F.CrtYd")
		)
		(fp_line
			(start 0.500126 -0.201422)
			(end 0.500126 1.598422)
			(stroke
				(width 0.1)
				(type default)
			)
			(layer "F.Fab")
		)
		(fp_line
			(start -0.500126 -0.201422)
			(end 0.500126 -0.201422)
			(stroke
				(width 0.1)
				(type default)
			)
			(layer "F.Fab")
		)
		(fp_line
			(start 0.500126 1.598422)
			(end -0.500126 1.598422)
			(stroke
				(width 0.1)
				(type default)
			)
			(layer "F.Fab")
		)
		(fp_line
			(start -0.500126 1.598422)
			(end -0.500126 -0.201422)
			(stroke
				(width 0.1)
				(type default)
			)
			(layer "F.Fab")
		)
		(pad "1" smd rect
			(at 0 0)
			(size 0.889 0.9906)
			(layers "F.Cu" "F.Mask" "F.Paste")
			(net "PVDDQ_KLM")
		)
		(pad "2" smd rect
			(at 0 1.397)
			(size 0.889 0.9906)
			(layers "F.Cu" "F.Mask" "F.Paste")
			(net "GND")
		)
		(zone
			(layer "F.Cu")
			(hatch none 0.5)
			(connect_pads
				(clearance 0)
			)
			(min_thickness 0.25)
			(keepout
				(tracks not_allowed)
				(vias allowed)
				(pads allowed)
				(copperpour not_allowed)
				(footprints allowed)
			)
			(placement
				(enabled no)
				(sheetname "")
			)
			(fill
				(thermal_gap 0.5)
				(thermal_bridge_width 0.5)
				(island_removal_mode 0)
			)
			(polygon
				(pts
					(xy 108.8136 -149.3139) (xy 108.8136 -150.3045) (xy 108.3056 -150.3045) (xy 108.3056 -149.3139)
				)
			)
		)
		(zone
			(layer "F.Cu")
			(hatch none 0.5)
			(connect_pads
				(clearance 0)
			)
			(min_thickness 0.25)
			(keepout
				(tracks allowed)
				(vias not_allowed)
				(pads allowed)
				(copperpour not_allowed)
				(footprints allowed)
			)
			(placement
				(enabled no)
				(sheetname "")
			)
			(fill
				(thermal_gap 0.5)
				(thermal_bridge_width 0.5)
				(island_removal_mode 0)
			)
			(polygon
				(pts
					(xy 108.8136 -149.3139) (xy 108.8136 -150.3045) (xy 108.3056 -150.3045) (xy 108.3056 -149.3139)
				)
			)
		)
	)
	(footprint ""
		(layer "F.Cu")
		(at 469.3031 -25.18156 180)
		(property "Reference" "C8E12"
			(at 0 0 180)
			(layer "F.SilkS")
			(hide yes)
			(effects
				(font
					(size 1.27 1.27)
				)
			)
		)
		(property "Value" ""
			(at 0 0 180)
			(layer "F.Fab")
			(effects
				(font
					(size 1.27 1.27)
				)
			)
		)
		(duplicate_pad_numbers_are_jumpers no)
		(fp_rect
			(start 0.4953 -0.2032)
			(end -0.4953 1.6002)
			(stroke
				(width 0)
				(type default)
			)
			(fill no)
			(layer "F.CrtYd")
		)
		(fp_line
			(start 0.4953 1.6002)
			(end -0.4953 1.6002)
			(stroke
				(width 0.1)
				(type default)
			)
			(layer "F.Fab")
		)
		(fp_line
			(start 0.4953 -0.2032)
			(end 0.4953 1.6002)
			(stroke
				(width 0.1)
				(type default)
			)
			(layer "F.Fab")
		)
		(fp_line
			(start -0.4953 1.6002)
			(end -0.4953 -0.2032)
			(stroke
				(width 0.1)
				(type default)
			)
			(layer "F.Fab")
		)
		(fp_line
			(start -0.4953 -0.2032)
			(end 0.4953 -0.2032)
			(stroke
				(width 0.1)
				(type default)
			)
			(layer "F.Fab")
		)
		(pad "1" smd rect
			(at 0 0 180)
			(size 0.762 0.889)
			(layers "F.Cu" "F.Mask" "F.Paste")
			(net "VR_P3V3_STBY_PHASE")
		)
		(pad "2" smd rect
			(at 0 1.397 180)
			(size 0.762 0.889)
			(layers "F.Cu" "F.Mask" "F.Paste")
			(net "VR_P3V3_STBY_BOOT_R")
		)
		(zone
			(layer "F.Cu")
			(hatch none 0.5)
			(connect_pads
				(clearance 0)
			)
			(min_thickness 0.25)
			(keepout
				(tracks not_allowed)
				(vias allowed)
				(pads allowed)
				(copperpour not_allowed)
				(footprints allowed)
			)
			(placement
				(enabled no)
				(sheetname "")
			)
			(fill
				(thermal_gap 0.5)
				(thermal_bridge_width 0.5)
				(island_removal_mode 0)
			)
			(polygon
				(pts
					(xy 468.9221 -25.62606) (xy 469.6841 -25.62606) (xy 469.6841 -26.13406) (xy 468.9221 -26.13406)
				)
			)
		)
	)
	(footprint ""
		(layer "F.Cu")
		(at 323.723 -34.163 90)
		(property "Reference" "R6F4"
			(at 0 0 90)
			(layer "F.SilkS")
			(hide yes)
			(effects
				(font
					(size 1.27 1.27)
				)
			)
		)
		(property "Value" ""
			(at 0 0 90)
			(layer "F.Fab")
			(effects
				(font
					(size 1.27 1.27)
				)
			)
		)
		(duplicate_pad_numbers_are_jumpers no)
		(fp_poly
			(pts
				(xy -0.2794 -0.1016) (xy 0.2794 -0.1016) (xy 0.2794 0.9906) (xy -0.2794 0.9906)
			)
			(stroke
				(width 0)
				(type default)
			)
			(fill no)
			(layer "F.CrtYd")
		)
		(fp_line
			(start 0.2794 -0.1016)
			(end -0.2794 -0.1016)
			(stroke
				(width 0.1)
				(type default)
			)
			(layer "F.Fab")
		)
		(fp_line
			(start -0.2794 -0.1016)
			(end -0.2794 0.9906)
			(stroke
				(width 0.1)
				(type default)
			)
			(layer "F.Fab")
		)
		(fp_line
			(start 0.2794 0.9906)
			(end 0.2794 -0.1016)
			(stroke
				(width 0.1)
				(type default)
			)
			(layer "F.Fab")
		)
		(fp_line
			(start -0.2794 0.9906)
			(end 0.2794 0.9906)
			(stroke
				(width 0.1)
				(type default)
			)
			(layer "F.Fab")
		)
		(pad "1" smd rect
			(at 0 0 90)
			(size 0.508 0.508)
			(layers "F.Cu" "F.Mask" "F.Paste")
			(net "IRQ_DIMM_SAVE_N")
		)
		(pad "2" smd rect
			(at 0 0.889 90)
			(size 0.508 0.508)
			(layers "F.Cu" "F.Mask" "F.Paste")
			(net "FM_ADR_COMPLETE_ABC_N")
		)
		(zone
			(layer "F.Cu")
			(hatch none 0.5)
			(connect_pads
				(clearance 0)
			)
			(min_thickness 0.25)
			(keepout
				(tracks allowed)
				(vias not_allowed)
				(pads allowed)
				(copperpour not_allowed)
				(footprints allowed)
			)
			(placement
				(enabled no)
				(sheetname "")
			)
			(fill
				(thermal_gap 0.5)
				(thermal_bridge_width 0.5)
				(island_removal_mode 0)
			)
			(polygon
				(pts
					(xy 323.977 -33.909) (xy 323.977 -34.417) (xy 324.358 -34.417) (xy 324.358 -33.909)
				)
			)
		)
		(zone
			(layer "F.Cu")
			(hatch none 0.5)
			(connect_pads
				(clearance 0)
			)
			(min_thickness 0.25)
			(keepout
				(tracks not_allowed)
				(vias allowed)
				(pads allowed)
				(copperpour not_allowed)
				(footprints allowed)
			)
			(placement
				(enabled no)
				(sheetname "")
			)
			(fill
				(thermal_gap 0.5)
				(thermal_bridge_width 0.5)
				(island_removal_mode 0)
			)
			(polygon
				(pts
					(xy 324.358 -33.909) (xy 324.358 -34.417) (xy 323.977 -34.417) (xy 323.977 -33.909)
				)
			)
		)
	)
	(footprint ""
		(layer "F.Cu")
		(at 461.098392 -37.067998 180)
		(property "Reference" "R9F13"
			(at 0 0 180)
			(layer "F.SilkS")
			(hide yes)
			(effects
				(font
					(size 1.27 1.27)
				)
			)
		)
		(property "Value" ""
			(at 0 0 180)
			(layer "F.Fab")
			(effects
				(font
					(size 1.27 1.27)
				)
			)
		)
		(duplicate_pad_numbers_are_jumpers no)
		(fp_poly
			(pts
				(xy -0.2794 -0.1016) (xy 0.2794 -0.1016) (xy 0.2794 0.9906) (xy -0.2794 0.9906)
			)
			(stroke
				(width 0)
				(type default)
			)
			(fill no)
			(layer "F.CrtYd")
		)
		(fp_line
			(start 0.2794 0.9906)
			(end 0.2794 -0.1016)
			(stroke
				(width 0.1)
				(type default)
			)
			(layer "F.Fab")
		)
		(fp_line
			(start 0.2794 -0.1016)
			(end -0.2794 -0.1016)
			(stroke
				(width 0.1)
				(type default)
			)
			(layer "F.Fab")
		)
		(fp_line
			(start -0.2794 0.9906)
			(end 0.2794 0.9906)
			(stroke
				(width 0.1)
				(type default)
			)
			(layer "F.Fab")
		)
		(fp_line
			(start -0.2794 -0.1016)
			(end -0.2794 0.9906)
			(stroke
				(width 0.1)
				(type default)
			)
			(layer "F.Fab")
		)
		(pad "1" smd rect
			(at 0 0 180)
			(size 0.508 0.508)
			(layers "F.Cu" "F.Mask" "F.Paste")
			(net "P3V3_STBY")
		)
		(pad "2" smd rect
			(at 0 0.889 180)
			(size 0.508 0.508)
			(layers "F.Cu" "F.Mask" "F.Paste")
			(net "PWRGD_P1V15_BMC_STBY_R")
		)
		(zone
			(layer "F.Cu")
			(hatch none 0.5)
			(connect_pads
				(clearance 0)
			)
			(min_thickness 0.25)
			(keepout
				(tracks not_allowed)
				(vias allowed)
				(pads allowed)
				(copperpour not_allowed)
				(footprints allowed)
			)
			(placement
				(enabled no)
				(sheetname "")
			)
			(fill
				(thermal_gap 0.5)
				(thermal_bridge_width 0.5)
				(island_removal_mode 0)
			)
			(polygon
				(pts
					(xy 461.352392 -37.702998) (xy 460.844392 -37.702998) (xy 460.844392 -37.321998) (xy 461.352392 -37.321998)
				)
			)
		)
		(zone
			(layer "F.Cu")
			(hatch none 0.5)
			(connect_pads
				(clearance 0)
			)
			(min_thickness 0.25)
			(keepout
				(tracks allowed)
				(vias not_allowed)
				(pads allowed)
				(copperpour not_allowed)
				(footprints allowed)
			)
			(placement
				(enabled no)
				(sheetname "")
			)
			(fill
				(thermal_gap 0.5)
				(thermal_bridge_width 0.5)
				(island_removal_mode 0)
			)
			(polygon
				(pts
					(xy 461.352392 -37.321998) (xy 460.844392 -37.321998) (xy 460.844392 -37.702998) (xy 461.352392 -37.702998)
				)
			)
		)
	)
	(footprint ""
		(layer "F.Cu")
		(at 489.077 -33.655 -90)
		(property "Reference" "R25W128"
			(at -0.8382 -0.67818 270)
			(unlocked yes)
			(layer "F.SilkS")
			(effects
				(font
					(size 0.4064 0.254)
					(thickness 0.1524)
				)
				(justify left)
			)
		)
		(property "Value" ""
			(at 0 0 270)
			(layer "F.Fab")
			(effects
				(font
					(size 1.27 1.27)
				)
			)
		)
		(duplicate_pad_numbers_are_jumpers no)
		(fp_poly
			(pts
				(xy -0.2794 -0.1016) (xy 0.2794 -0.1016) (xy 0.2794 0.9906) (xy -0.2794 0.9906)
			)
			(stroke
				(width 0)
				(type default)
			)
			(fill no)
			(layer "F.CrtYd")
		)
		(fp_line
			(start -0.2794 0.9906)
			(end 0.2794 0.9906)
			(stroke
				(width 0.1)
				(type default)
			)
			(layer "F.Fab")
		)
		(fp_line
			(start 0.2794 0.9906)
			(end 0.2794 -0.1016)
			(stroke
				(width 0.1)
				(type default)
			)
			(layer "F.Fab")
		)
		(fp_line
			(start -0.2794 -0.1016)
			(end -0.2794 0.9906)
			(stroke
				(width 0.1)
				(type default)
			)
			(layer "F.Fab")
		)
		(fp_line
			(start 0.2794 -0.1016)
			(end -0.2794 -0.1016)
			(stroke
				(width 0.1)
				(type default)
			)
			(layer "F.Fab")
		)
		(pad "1" smd rect
			(at 0 0 270)
			(size 0.508 0.508)
			(layers "F.Cu" "F.Mask" "F.Paste")
			(net "V_IO_R_J")
		)
		(pad "2" smd rect
			(at 0 0.889 270)
			(size 0.508 0.508)
			(layers "F.Cu" "F.Mask" "F.Paste")
			(net "GND")
		)
		(zone
			(layer "F.Cu")
			(hatch none 0.5)
			(connect_pads
				(clearance 0)
			)
			(min_thickness 0.25)
			(keepout
				(tracks not_allowed)
				(vias allowed)
				(pads allowed)
				(copperpour not_allowed)
				(footprints allowed)
			)
			(placement
				(enabled no)
				(sheetname "")
			)
			(fill
				(thermal_gap 0.5)
				(thermal_bridge_width 0.5)
				(island_removal_mode 0)
			)
			(polygon
				(pts
					(xy 488.442 -33.909) (xy 488.442 -33.401) (xy 488.823 -33.401) (xy 488.823 -33.909)
				)
			)
		)
		(zone
			(layer "F.Cu")
			(hatch none 0.5)
			(connect_pads
				(clearance 0)
			)
			(min_thickness 0.25)
			(keepout
				(tracks allowed)
				(vias not_allowed)
				(pads allowed)
				(copperpour not_allowed)
				(footprints allowed)
			)
			(placement
				(enabled no)
				(sheetname "")
			)
			(fill
				(thermal_gap 0.5)
				(thermal_bridge_width 0.5)
				(island_removal_mode 0)
			)
			(polygon
				(pts
					(xy 488.823 -33.909) (xy 488.823 -33.401) (xy 488.442 -33.401) (xy 488.442 -33.909)
				)
			)
		)
	)
	(footprint ""
		(layer "F.Cu")
		(at 13.35278 -154.178 -90)
		(property "Reference" "R1A1"
			(at 0 0 270)
			(layer "F.SilkS")
			(hide yes)
			(effects
				(font
					(size 1.27 1.27)
				)
			)
		)
		(property "Value" ""
			(at 0 0 270)
			(layer "F.Fab")
			(effects
				(font
					(size 1.27 1.27)
				)
			)
		)
		(duplicate_pad_numbers_are_jumpers no)
		(fp_rect
			(start 0.4953 1.6002)
			(end -0.4953 -0.2032)
			(stroke
				(width 0)
				(type default)
			)
			(fill no)
			(layer "F.CrtYd")
		)
		(fp_line
			(start -0.4953 1.6002)
			(end -0.4953 -0.2032)
			(stroke
				(width 0.1)
				(type default)
			)
			(layer "F.Fab")
		)
		(fp_line
			(start 0.4953 1.6002)
			(end -0.4953 1.6002)
			(stroke
				(width 0.1)
				(type default)
			)
			(layer "F.Fab")
		)
		(fp_line
			(start -0.4953 -0.2032)
			(end 0.4953 -0.2032)
			(stroke
				(width 0.1)
				(type default)
			)
			(layer "F.Fab")
		)
		(fp_line
			(start 0.4953 -0.2032)
			(end 0.4953 1.6002)
			(stroke
				(width 0.1)
				(type default)
			)
			(layer "F.Fab")
		)
		(pad "1" smd rect
			(at 0 0 270)
			(size 0.762 0.889)
			(layers "F.Cu" "F.Mask" "F.Paste")
			(net "PVDDQ_KLM")
		)
		(pad "2" smd rect
			(at 0 1.397 270)
			(size 0.762 0.889)
			(layers "F.Cu" "F.Mask" "F.Paste")
			(net "GND")
		)
		(zone
			(layer "F.Cu")
			(hatch none 0.5)
			(connect_pads
				(clearance 0)
			)
			(min_thickness 0.25)
			(keepout
				(tracks allowed)
				(vias not_allowed)
				(pads allowed)
				(copperpour not_allowed)
				(footprints allowed)
			)
			(placement
				(enabled no)
				(sheetname "")
			)
			(fill
				(thermal_gap 0.5)
				(thermal_bridge_width 0.5)
				(island_removal_mode 0)
			)
			(polygon
				(pts
					(xy 12.40028 -153.797) (xy 12.90828 -153.797) (xy 12.90828 -154.559) (xy 12.40028 -154.559)
				)
			)
		)
		(zone
			(layer "F.Cu")
			(hatch none 0.5)
			(connect_pads
				(clearance 0)
			)
			(min_thickness 0.25)
			(keepout
				(tracks not_allowed)
				(vias allowed)
				(pads allowed)
				(copperpour not_allowed)
				(footprints allowed)
			)
			(placement
				(enabled no)
				(sheetname "")
			)
			(fill
				(thermal_gap 0.5)
				(thermal_bridge_width 0.5)
				(island_removal_mode 0)
			)
			(polygon
				(pts
					(xy 12.40028 -153.797) (xy 12.90828 -153.797) (xy 12.90828 -154.559) (xy 12.40028 -154.559)
				)
			)
		)
	)
	(footprint ""
		(layer "F.Cu")
		(at 28.380182 -140.1826 -90)
		(property "Reference" "C1A16"
			(at 0 0 270)
			(layer "F.SilkS")
			(hide yes)
			(effects
				(font
					(size 1.27 1.27)
				)
			)
		)
		(property "Value" ""
			(at 0 0 270)
			(layer "F.Fab")
			(effects
				(font
					(size 1.27 1.27)
				)
			)
		)
		(duplicate_pad_numbers_are_jumpers no)
		(fp_poly
			(pts
				(xy -0.7239 -0.2159) (xy 0.7239 -0.2159) (xy 0.7239 1.9939) (xy -0.7239 1.9939)
			)
			(stroke
				(width 0)
				(type default)
			)
			(fill no)
			(layer "F.CrtYd")
		)
		(fp_line
			(start -0.7239 1.9939)
			(end 0.7239 1.9939)
			(stroke
				(width 0.1)
				(type default)
			)
			(layer "F.Fab")
		)
		(fp_line
			(start 0.7239 1.9939)
			(end 0.7239 -0.2159)
			(stroke
				(width 0.1)
				(type default)
			)
			(layer "F.Fab")
		)
		(fp_line
			(start -0.7239 -0.2159)
			(end -0.7239 1.9939)
			(stroke
				(width 0.1)
				(type default)
			)
			(layer "F.Fab")
		)
		(fp_line
			(start 0.7239 -0.2159)
			(end -0.7239 -0.2159)
			(stroke
				(width 0.1)
				(type default)
			)
			(layer "F.Fab")
		)
		(pad "1" smd rect
			(at 0 0 270)
			(size 1.27 1.016)
			(layers "F.Cu" "F.Mask" "F.Paste")
			(net "P12V_NVDIMM_KLM")
		)
		(pad "2" smd rect
			(at 0 1.778 270)
			(size 1.27 1.016)
			(layers "F.Cu" "F.Mask" "F.Paste")
			(net "GND")
		)
		(zone
			(layer "F.Cu")
			(hatch none 0.5)
			(connect_pads
				(clearance 0)
			)
			(min_thickness 0.25)
			(keepout
				(tracks not_allowed)
				(vias allowed)
				(pads allowed)
				(copperpour not_allowed)
				(footprints allowed)
			)
			(placement
				(enabled no)
				(sheetname "")
			)
			(fill
				(thermal_gap 0.5)
				(thermal_bridge_width 0.5)
				(island_removal_mode 0)
			)
			(polygon
				(pts
					(xy 27.872182 -140.8176) (xy 27.872182 -139.5476) (xy 27.110182 -139.5476) (xy 27.110182 -140.8176)
				)
			)
		)
	)
)
